(kicad_pcb
	(version 20260206)
	(generator "pcbnew")
	(generator_version "10.0")
	(general
		(thickness 1.21888)
		(legacy_teardrops no)
	)
	(paper "A4")
	(title_block
		(title "timecard-proto-v0 — Timingcard_PCB.PcbDoc")
		(comment 1 "Time Appliance Project (Time Card) / footprints 72-84 of 167")
	)
	(layers
		(0 "F.Cu" signal "TOP")
		(4 "In1.Cu" signal "SGND")
		(6 "In2.Cu" signal "IN1")
		(8 "In3.Cu" signal "IN2")
		(10 "In4.Cu" signal "SGND1")
		(2 "B.Cu" signal "BOTTOM")
		(9 "F.Adhes" user "F.Adhesive")
		(11 "B.Adhes" user "B.Adhesive")
		(13 "F.Paste" user "Top Paste")
		(15 "B.Paste" user "Bottom Paste")
		(5 "F.SilkS" user "Top Overlay")
		(7 "B.SilkS" user "Bottom Overlay")
		(1 "F.Mask" user "Top Solder")
		(3 "B.Mask" user "Bottom Solder")
		(17 "Dwgs.User" user "User.Drawings")
		(19 "Cmts.User" user "User.Comments")
		(21 "Eco1.User" user "User.Eco1")
		(23 "Eco2.User" user "User.Eco2")
		(25 "Edge.Cuts" user)
		(27 "Margin" user)
		(31 "F.CrtYd" user "Top Courtyard")
		(29 "B.CrtYd" user "Bottom Courtyard")
		(35 "F.Fab" user "Top Component Center")
		(33 "B.Fab" user "Bottom Component Center")
	)
	(footprint "Capacitors:CAPC2012X14N"
		(layer "F.Cu")
		(at 105.169795 51.9666)
		(property "Reference" "C91"
			(at 3.331655 1.33307 90)
			(unlocked yes)
			(layer "F.SilkS")
			(effects
				(font
					(size 0.762 0.762)
					(thickness 0.2286)
				)
				(justify left bottom)
			)
		)
		(property "Value" "CAP_0805_1UF_25V"
			(at -1.5875 3.52679 0)
			(unlocked yes)
			(layer "F.SilkS")
			(hide yes)
			(effects
				(font
					(size 1.524 1.524)
					(thickness 0.254)
				)
				(justify left bottom)
			)
		)
		(sheetname "GPS_IMU_SENSORS")
		(sheetfile "GPS_IMU_SENSORS.kicad_sch")
		(duplicate_pad_numbers_are_jumpers no)
		(fp_line
			(start -0.762 -0.9652)
			(end 0.762 -0.9652)
			(stroke
				(width 0.1524)
				(type solid)
			)
			(layer "F.SilkS")
		)
		(fp_line
			(start -0.762 0.9652)
			(end 0.762 0.9652)
			(stroke
				(width 0.1524)
				(type solid)
			)
			(layer "F.SilkS")
		)
		(pad "1" smd rect
			(at -0.9 0 90)
			(size 1.45 1.15)
			(layers "F.Cu" "F.Mask" "F.Paste")
			(net "GND")
		)
		(pad "2" smd rect
			(at 0.9 0 90)
			(size 1.45 1.15)
			(layers "F.Cu" "F.Mask" "F.Paste")
			(net "+5.0V")
		)
	)
	(footprint "Miscellaneous Devices:J1-0603"
		(layer "F.Cu")
		(at 114.688595 57.8286 -90)
		(property "Reference" "R13"
			(at 0.2786 -5.873079 270)
			(unlocked yes)
			(layer "F.SilkS")
			(effects
				(font
					(size 0.762 0.762)
					(thickness 0.2286)
				)
			)
		)
		(property "Value" "MACRX"
			(at 2.835402 -4.96595 0)
			(unlocked yes)
			(layer "F.SilkS")
			(hide yes)
			(effects
				(font
					(size 1.524 1.524)
					(thickness 0.254)
				)
			)
		)
		(sheetname "GPS_IMU_SENSORS")
		(sheetfile "GPS_IMU_SENSORS.kicad_sch")
		(duplicate_pad_numbers_are_jumpers no)
		(fp_line
			(start 0.2 0.35)
			(end -0.2 0.35)
			(stroke
				(width 0.2)
				(type solid)
			)
			(layer "F.SilkS")
		)
		(fp_line
			(start 0.2 -0.35)
			(end -0.2 -0.35)
			(stroke
				(width 0.2)
				(type solid)
			)
			(layer "F.SilkS")
		)
		(pad "1" smd rect
			(at -0.75 0)
			(size 0.9 0.7)
			(layers "F.Cu" "F.Mask" "F.Paste")
			(net "MAC_RX")
		)
		(pad "2" smd rect
			(at 0.75 0)
			(size 0.9 0.7)
			(layers "F.Cu" "F.Mask" "F.Paste")
			(net "NetJP2_3")
		)
	)
	(footprint "Vault:RESC1608X50X30NL20T20"
		(layer "F.Cu")
		(at 152.083595 62.5076 180)
		(property "Reference" "R25"
			(at 1.34571 0.656145 0)
			(unlocked yes)
			(layer "F.SilkS")
			(effects
				(font
					(size 0.762 0.762)
					(thickness 0.2286)
				)
				(justify left bottom)
			)
		)
		(property "Value" "499 OHM"
			(at 0.2413 -3.42519 0)
			(unlocked yes)
			(layer "F.SilkS")
			(hide yes)
			(effects
				(font
					(size 1.524 1.524)
					(thickness 0.254)
				)
				(justify left bottom)
			)
		)
		(sheetname "UART")
		(sheetfile "UART.kicad_sch")
		(duplicate_pad_numbers_are_jumpers no)
		(pad "1" smd rect
			(at -0.65 0 270)
			(size 1 0.9)
			(layers "F.Cu" "F.Mask" "F.Paste")
			(net "UART1_RXD")
		)
		(pad "2" smd rect
			(at 0.65 0 270)
			(size 1 0.9)
			(layers "F.Cu" "F.Mask" "F.Paste")
			(net "NetD9_1")
		)
	)
	(footprint "Vault:TECO-1909763-1_V"
		(layer "F.Cu")
		(at 75.088595 124.1786 90)
		(property "Reference" "J9"
			(at -3.026931 2.028605 0)
			(unlocked yes)
			(layer "F.SilkS")
			(effects
				(font
					(size 0.762 0.762)
					(thickness 0.2286)
				)
			)
		)
		(property "Value" "1909763-1"
			(at 4.608085 3.749802 90)
			(unlocked yes)
			(layer "F.SilkS")
			(hide yes)
			(effects
				(font
					(size 1.524 1.524)
					(thickness 0.254)
				)
			)
		)
		(sheetname "USER_IO")
		(sheetfile "USER_IO.kicad_sch")
		(duplicate_pad_numbers_are_jumpers no)
		(fp_line
			(start -0.55 -1.3)
			(end 0.55 -1.3)
			(stroke
				(width 0.2)
				(type solid)
			)
			(layer "F.SilkS")
		)
		(fp_circle
			(center -1.778 1.65)
			(end -1.653 1.65)
			(stroke
				(width 0.25)
				(type solid)
			)
			(fill no)
			(layer "F.SilkS")
		)
		(pad "1" smd rect
			(at -1.475 0 90)
			(size 1.05 2.2)
			(layers "F.Cu" "F.Mask" "F.Paste")
			(net "GND")
		)
		(pad "2" smd rect
			(at 0 1.525 90)
			(size 1 1.05)
			(layers "F.Cu" "F.Mask" "F.Paste")
			(net "ANT3")
		)
		(pad "3" smd rect
			(at 1.475 0 90)
			(size 1.05 2.2)
			(layers "F.Cu" "F.Mask" "F.Paste")
			(net "GND")
		)
	)
	(footprint "Capacitors:CAPC2012X14N"
		(layer "F.Cu")
		(at 159.068595 89.0506 90)
		(property "Reference" "C74"
			(at -0.664655 -4.87631 0)
			(unlocked yes)
			(layer "F.SilkS")
			(effects
				(font
					(size 0.762 0.762)
					(thickness 0.2286)
				)
				(justify left bottom)
			)
		)
		(property "Value" "CAP_0805_22UF_16V"
			(at -3.52679 -1.5875 0)
			(unlocked yes)
			(layer "F.SilkS")
			(hide yes)
			(effects
				(font
					(size 1.524 1.524)
					(thickness 0.254)
				)
				(justify left bottom)
			)
		)
		(sheetname "MAC")
		(sheetfile "MAC.kicad_sch")
		(duplicate_pad_numbers_are_jumpers no)
		(fp_line
			(start -0.762 -0.9652)
			(end 0.762 -0.9652)
			(stroke
				(width 0.1524)
				(type solid)
			)
			(layer "F.SilkS")
		)
		(fp_line
			(start -0.762 0.9652)
			(end 0.762 0.9652)
			(stroke
				(width 0.1524)
				(type solid)
			)
			(layer "F.SilkS")
		)
		(pad "1" smd rect
			(at -0.9 0 180)
			(size 1.45 1.15)
			(layers "F.Cu" "F.Mask" "F.Paste")
			(net "GND")
		)
		(pad "2" smd rect
			(at 0.9 0 180)
			(size 1.45 1.15)
			(layers "F.Cu" "F.Mask" "F.Paste")
			(net "+3.3V_CLEAN")
		)
	)
	(footprint "Passives:DIOM1608X06N"
		(layer "F.Cu")
		(at 79.989925 53.2366 90)
		(property "Reference" "D12"
			(at -1.45369 -1.231865 90)
			(unlocked yes)
			(layer "F.SilkS")
			(effects
				(font
					(size 0.762 0.762)
					(thickness 0.2286)
				)
				(justify left bottom)
			)
		)
		(property "Value" "RED"
			(at -4.13639 -0.5715 0)
			(unlocked yes)
			(layer "F.SilkS")
			(hide yes)
			(effects
				(font
					(size 1.524 1.524)
					(thickness 0.254)
				)
				(justify left bottom)
			)
		)
		(sheetname "USER_IO")
		(sheetfile "USER_IO.kicad_sch")
		(duplicate_pad_numbers_are_jumpers no)
		(fp_circle
			(center -1.275 -0.725)
			(end -1.225 -0.725)
			(stroke
				(width 0.1)
				(type solid)
			)
			(fill no)
			(layer "F.SilkS")
		)
		(pad "1" smd rect
			(at -0.725 0 180)
			(size 0.85 1)
			(layers "F.Cu" "F.Mask" "F.Paste")
			(net "NetD12_1")
		)
		(pad "2" smd rect
			(at 0.725 0 180)
			(size 0.85 1)
			(layers "F.Cu" "F.Mask" "F.Paste")
			(net "+3.3V")
		)
	)
	(footprint "Capacitors:CAPC1608X10N"
		(layer "F.Cu")
		(at 222.822595 102.8936 90)
		(property "Reference" "C3"
			(at -3.16 0.509345 90)
			(unlocked yes)
			(layer "F.SilkS")
			(effects
				(font
					(size 0.762 0.762)
					(thickness 0.2286)
				)
				(justify left bottom)
			)
		)
		(property "Value" "CAP_0603_0.01UF_50V"
			(at 12.98321 3.9751 0)
			(unlocked yes)
			(layer "F.SilkS")
			(hide yes)
			(effects
				(font
					(size 1.524 1.524)
					(thickness 0.254)
				)
				(justify left bottom)
			)
		)
		(sheetname "POWER")
		(sheetfile "POWER.kicad_sch")
		(duplicate_pad_numbers_are_jumpers no)
		(fp_line
			(start -0.635 -0.7112)
			(end 0.635 -0.7112)
			(stroke
				(width 0.1524)
				(type solid)
			)
			(layer "F.SilkS")
		)
		(fp_line
			(start -0.635 0.7112)
			(end 0.635 0.7112)
			(stroke
				(width 0.1524)
				(type solid)
			)
			(layer "F.SilkS")
		)
		(pad "1" smd rect
			(at -0.8 0 180)
			(size 0.95 1)
			(layers "F.Cu" "F.Mask" "F.Paste")
			(net "NetC3_1")
		)
		(pad "2" smd rect
			(at 0.8 0 180)
			(size 0.95 1)
			(layers "F.Cu" "F.Mask" "F.Paste")
			(net "NetC3_2")
		)
	)
	(footprint "Passives:SODFL370X135-2N"
		(layer "F.Cu")
		(at 217.742595 66.5716)
		(property "Reference" "D3"
			(at 3.439345 0.507 90)
			(unlocked yes)
			(layer "F.SilkS")
			(effects
				(font
					(size 0.762 0.762)
					(thickness 0.2286)
				)
				(justify left bottom)
			)
		)
		(property "Value" "DFLZ39-TP"
			(at -2.0955 3.62839 0)
			(unlocked yes)
			(layer "F.SilkS")
			(hide yes)
			(effects
				(font
					(size 1.524 1.524)
					(thickness 0.254)
				)
				(justify left bottom)
			)
		)
		(sheetname "POWER")
		(sheetfile "POWER.kicad_sch")
		(duplicate_pad_numbers_are_jumpers no)
		(fp_line
			(start -1.55 -0.95)
			(end 1.55 -0.95)
			(stroke
				(width 0.2)
				(type solid)
			)
			(layer "F.SilkS")
		)
		(fp_line
			(start -1.55 -0.825)
			(end -1.55 -0.95)
			(stroke
				(width 0.2)
				(type solid)
			)
			(layer "F.SilkS")
		)
		(fp_line
			(start -1.55 0.95)
			(end -1.55 0.825)
			(stroke
				(width 0.2)
				(type solid)
			)
			(layer "F.SilkS")
		)
		(fp_line
			(start -1.55 0.95)
			(end 1.55 0.95)
			(stroke
				(width 0.2)
				(type solid)
			)
			(layer "F.SilkS")
		)
		(fp_line
			(start 1.55 -0.825)
			(end 1.55 -0.95)
			(stroke
				(width 0.2)
				(type solid)
			)
			(layer "F.SilkS")
		)
		(fp_line
			(start 1.55 0.95)
			(end 1.55 0.825)
			(stroke
				(width 0.2)
				(type solid)
			)
			(layer "F.SilkS")
		)
		(fp_circle
			(center -2.05 -0.825)
			(end -2.05 -0.875)
			(stroke
				(width 0.1)
				(type solid)
			)
			(fill no)
			(layer "F.SilkS")
		)
		(pad "1" smd rect
			(at -1.825 0 90)
			(size 1.05 0.65)
			(layers "F.Cu" "F.Mask" "F.Paste")
			(net "NetD2_1")
		)
		(pad "2" smd rect
			(at 1.825 0 90)
			(size 1.05 0.65)
			(layers "F.Cu" "F.Mask" "F.Paste")
			(net "+12V_PCIE")
		)
	)
	(footprint "Connectors:USB_47346-1001"
		(layer "F.Cu")
		(at 119.035795 54.652 180)
		(property "Reference" "J4"
			(at -3.34281 -0.392255 0)
			(unlocked yes)
			(layer "F.SilkS")
			(effects
				(font
					(size 0.762 0.762)
					(thickness 0.2286)
				)
				(justify left bottom)
			)
		)
		(property "Value" "473461001"
			(at 3.1067 -2.01679 0)
			(unlocked yes)
			(layer "F.SilkS")
			(hide yes)
			(effects
				(font
					(size 1.524 1.524)
					(thickness 0.254)
				)
				(justify left bottom)
			)
		)
		(sheetname "GPS_IMU_SENSORS")
		(sheetfile "GPS_IMU_SENSORS.kicad_sch")
		(duplicate_pad_numbers_are_jumpers no)
		(fp_line
			(start 5.364 -0.254)
			(end 5.364 1.651)
			(stroke
				(width 0.1524)
				(type solid)
			)
			(layer "F.SilkS")
		)
		(fp_line
			(start -2.764 -0.254)
			(end -2.764 1.651)
			(stroke
				(width 0.1524)
				(type solid)
			)
			(layer "F.SilkS")
		)
		(fp_text user "1"
			(at -0.29131 -1.11 270)
			(unlocked yes)
			(layer "F.SilkS")
			(effects
				(font
					(size 1.524 1.524)
					(thickness 0.254)
				)
				(justify left bottom)
			)
		)
		(pad "0" smd rect
			(at -2.075 2.66 180)
			(size 1.65 1.3)
			(layers "F.Cu" "F.Mask" "F.Paste")
		)
		(pad "0" smd rect
			(at -1.2 0.085 180)
			(size 1.42 1.55)
			(layers "F.Cu" "F.Mask" "F.Paste")
		)
		(pad "0" smd rect
			(at 0.15 2.66 180)
			(size 1.8 1.9)
			(layers "F.Cu" "F.Mask" "F.Paste")
		)
		(pad "0" smd rect
			(at 2.85 2.66 180)
			(size 1 1.9)
			(layers "F.Cu" "F.Mask" "F.Paste")
		)
		(pad "0" smd rect
			(at 3.8 0.085 180)
			(size 1.42 1.55)
			(layers "F.Cu" "F.Mask" "F.Paste")
		)
		(pad "0" smd rect
			(at 4.675 2.66 180)
			(size 1.65 1.3)
			(layers "F.Cu" "F.Mask" "F.Paste")
		)
		(pad "1" smd rect
			(at 0 0 180)
			(size 0.45 1.38)
			(layers "F.Cu" "F.Mask" "F.Paste")
		)
		(pad "2" smd rect
			(at 0.65 0 180)
			(size 0.45 1.38)
			(layers "F.Cu" "F.Mask" "F.Paste")
			(net "NetJ4_2")
		)
		(pad "3" smd rect
			(at 1.3 0 180)
			(size 0.45 1.38)
			(layers "F.Cu" "F.Mask" "F.Paste")
			(net "NetJ4_3")
		)
		(pad "4" smd rect
			(at 1.95 0 180)
			(size 0.45 1.38)
			(layers "F.Cu" "F.Mask" "F.Paste")
		)
		(pad "5" smd rect
			(at 2.6 0 180)
			(size 0.45 1.38)
			(layers "F.Cu" "F.Mask" "F.Paste")
			(net "GND")
		)
	)
	(footprint "Resistors:RESC1608X50N"
		(layer "F.Cu")
		(at 236.288595 112.1786 90)
		(property "Reference" "R8"
			(at 1.5 0.393345 90)
			(unlocked yes)
			(layer "F.SilkS")
			(effects
				(font
					(size 0.762 0.762)
					(thickness 0.2286)
				)
				(justify left bottom)
			)
		)
		(property "Value" "ERJ-3EKF2201V"
			(at -3.04419 -4.4323 0)
			(unlocked yes)
			(layer "F.SilkS")
			(hide yes)
			(effects
				(font
					(size 1.524 1.524)
					(thickness 0.254)
				)
				(justify left bottom)
			)
		)
		(sheetname "POWER")
		(sheetfile "POWER.kicad_sch")
		(duplicate_pad_numbers_are_jumpers no)
		(fp_line
			(start 0 -0.5)
			(end 0 0.5)
			(stroke
				(width 0.1524)
				(type solid)
			)
			(layer "F.SilkS")
		)
		(pad "1" smd rect
			(at -0.69 0 180)
			(size 1 0.72)
			(layers "F.Cu" "F.Mask" "F.Paste")
			(net "GND")
		)
		(pad "2" smd rect
			(at 0.69 0 180)
			(size 1 0.72)
			(layers "F.Cu" "F.Mask" "F.Paste")
			(net "NetC20_1")
		)
	)
	(footprint "Connectors:AMPHENOL-901-143-6RFX"
		(layer "F.Cu")
		(at 63.564595 137.5646 180)
		(property "Reference" "AN4"
			(at -5.20749 -4.601655 0)
			(unlocked yes)
			(layer "F.SilkS")
			(effects
				(font
					(size 0.762 0.762)
					(thickness 0.2286)
				)
				(justify left bottom)
			)
		)
		(property "Value" "RF-901-143-6FRX"
			(at 4.6101 -12.21359 0)
			(unlocked yes)
			(layer "F.SilkS")
			(hide yes)
			(effects
				(font
					(size 1.524 1.524)
					(thickness 0.254)
				)
				(justify left bottom)
			)
		)
		(sheetfile ".kicad_sch")
		(duplicate_pad_numbers_are_jumpers no)
		(fp_line
			(start 4.318 3.556)
			(end 3.302 4.572)
			(stroke
				(width 0.1778)
				(type solid)
			)
			(layer "F.SilkS")
		)
		(fp_line
			(start 4.318 -3.556)
			(end 3.302 -4.572)
			(stroke
				(width 0.1778)
				(type solid)
			)
			(layer "F.SilkS")
		)
		(fp_line
			(start 3.302 4.572)
			(end 2.54 4.572)
			(stroke
				(width 0.1778)
				(type solid)
			)
			(layer "F.SilkS")
		)
		(fp_line
			(start 3.302 -4.572)
			(end 2.54 -4.572)
			(stroke
				(width 0.1778)
				(type solid)
			)
			(layer "F.SilkS")
		)
		(fp_line
			(start 2.54 4.572)
			(end -4.572 4.572)
			(stroke
				(width 0.1778)
				(type solid)
			)
			(layer "F.SilkS")
		)
		(fp_line
			(start 2.54 -4.572)
			(end -4.572 -4.572)
			(stroke
				(width 0.1778)
				(type solid)
			)
			(layer "F.SilkS")
		)
		(fp_line
			(start -4.572 2.54)
			(end -4.572 4.572)
			(stroke
				(width 0.1778)
				(type solid)
			)
			(layer "F.SilkS")
		)
		(fp_line
			(start -4.572 -4.572)
			(end -4.572 -2.54)
			(stroke
				(width 0.1778)
				(type solid)
			)
			(layer "F.SilkS")
		)
		(pad "1" thru_hole circle
			(at 0 0 180)
			(size 2.8448 2.8448)
			(drill 1.524)
			(layers "*.Cu" "*.Mask")
			(remove_unused_layers no)
			(net "ANT4")
			(thermal_bridge_angle 90)
		)
		(pad "2" thru_hole circle
			(at -2.54 2.54 180)
			(size 3.048 3.048)
			(drill 1.7272)
			(layers "*.Cu" "*.Mask")
			(remove_unused_layers no)
			(net "GND")
			(thermal_bridge_angle 90)
		)
		(pad "3" thru_hole circle
			(at -2.54 -2.54 180)
			(size 3.048 3.048)
			(drill 1.7272)
			(layers "*.Cu" "*.Mask")
			(remove_unused_layers no)
			(net "GND")
			(thermal_bridge_angle 90)
		)
		(pad "4" thru_hole circle
			(at 2.54 -2.54 180)
			(size 3.048 3.048)
			(drill 1.7272)
			(layers "*.Cu" "*.Mask")
			(remove_unused_layers no)
			(net "GND")
			(thermal_bridge_angle 90)
		)
		(pad "5" thru_hole circle
			(at 2.54 2.54 180)
			(size 3.048 3.048)
			(drill 1.7272)
			(layers "*.Cu" "*.Mask")
			(remove_unused_layers no)
			(net "GND")
			(thermal_bridge_angle 90)
		)
	)
	(footprint "Vault:RESC1608X55X30NL15T15"
		(layer "F.Cu")
		(at 74.788595 56.9786 90)
		(property "Reference" "R16"
			(at 0.154 -1.673069 90)
			(unlocked yes)
			(layer "F.SilkS")
			(effects
				(font
					(size 0.762 0.762)
					(thickness 0.254)
				)
			)
		)
		(property "Value" "200 OHM"
			(at -2.085402 4.85075 0)
			(unlocked yes)
			(layer "F.SilkS")
			(hide yes)
			(effects
				(font
					(size 1.524 1.524)
					(thickness 0.254)
				)
			)
		)
		(sheetname "USER_IO")
		(sheetfile "USER_IO.kicad_sch")
		(duplicate_pad_numbers_are_jumpers no)
		(pad "1" smd rect
			(at -0.675 0 180)
			(size 0.95 0.8)
			(layers "F.Cu" "F.Mask" "F.Paste")
			(net "LED1")
		)
		(pad "2" smd rect
			(at 0.675 0 180)
			(size 0.95 0.8)
			(layers "F.Cu" "F.Mask" "F.Paste")
			(net "NetD11_1")
		)
	)
	(footprint "Resistors:RESC1608X50N"
		(layer "F.Cu")
		(at 232.982595 114.4506)
		(property "Reference" "R4"
			(at -0.619 1.771345 0)
			(unlocked yes)
			(layer "F.SilkS")
			(effects
				(font
					(size 0.762 0.762)
					(thickness 0.2286)
				)
				(justify left bottom)
			)
		)
		(property "Value" "ERJ-3EKF4702V"
			(at -4.4323 3.04419 0)
			(unlocked yes)
			(layer "F.SilkS")
			(hide yes)
			(effects
				(font
					(size 1.524 1.524)
					(thickness 0.254)
				)
				(justify left bottom)
			)
		)
		(sheetname "POWER")
		(sheetfile "POWER.kicad_sch")
		(duplicate_pad_numbers_are_jumpers no)
		(fp_line
			(start 0 0.5)
			(end 0 -0.5)
			(stroke
				(width 0.1524)
				(type solid)
			)
			(layer "F.SilkS")
		)
		(pad "1" smd rect
			(at -0.69 0 90)
			(size 1 0.72)
			(layers "F.Cu" "F.Mask" "F.Paste")
			(net "+5.0V")
		)
		(pad "2" smd rect
			(at 0.69 0 90)
			(size 1 0.72)
			(layers "F.Cu" "F.Mask" "F.Paste")
			(net "NetR4_2")
		)
	)
)
